(kicad_pcb
	(version 20260206)
	(generator "pcbnew")
	(generator_version "10.0")
	(general
		(thickness 1.6)
		(legacy_teardrops no)
	)
	(paper "A4")
	(title_block
		(title "03242023_DA0F0TMBIJ0_F0T_Motherboard_J_brd_V01_OCP.brd")
		(comment 1 "Grand Teton / footprint 3039 of 6105 (U2), pads 319-426 of 4677")
	)
	(layers
		(0 "F.Cu" signal "TOP")
		(4 "In1.Cu" signal "GND")
		(6 "In2.Cu" signal "IN1")
		(8 "In3.Cu" signal "GND1")
		(10 "In4.Cu" signal "IN2")
		(12 "In5.Cu" signal "GND2")
		(14 "In6.Cu" signal "IN3")
		(16 "In7.Cu" signal "GND3")
		(18 "In8.Cu" signal "VCC")
		(20 "In9.Cu" signal "VCC1")
		(22 "In10.Cu" signal "GND4")
		(24 "In11.Cu" signal "IN4")
		(26 "In12.Cu" signal "GND5")
		(28 "In13.Cu" signal "IN5")
		(30 "In14.Cu" signal "GND6")
		(32 "In15.Cu" signal "IN6")
		(34 "In16.Cu" signal "GND7")
		(2 "B.Cu" signal "BOTTOM")
		(9 "F.Adhes" user "F.Adhesive")
		(11 "B.Adhes" user "B.Adhesive")
		(13 "F.Paste" user "Package Geometry/Pastemask Top")
		(15 "B.Paste" user "Package Geometry/Pastemask Bottom")
		(5 "F.SilkS" user "Ref Des/Silkscreen Top")
		(7 "B.SilkS" user "Ref Des/Silkscreen Bottom")
		(1 "F.Mask" user "Board Geometry/Soldermask Top")
		(3 "B.Mask" user "Board Geometry/Soldermask Bottom")
		(17 "Dwgs.User" user "User.Drawings")
		(19 "Cmts.User" user "User.Comments")
		(21 "Eco1.User" user "User.Eco1")
		(23 "Eco2.User" user "User.Eco2")
		(25 "Edge.Cuts" user "Board Geometry/Outline")
		(27 "Margin" user)
		(31 "F.CrtYd" user "Package Geometry/Place Bound Top")
		(29 "B.CrtYd" user "Package Geometry/Place Bound Bottom")
		(35 "F.Fab" user "Ref Des/Assembly Top")
		(33 "B.Fab" user "Ref Des/Assembly Bottom")
	)
	(footprint ""
		(layer "F.Cu")
		(at 359.870248 -251.76988 90)
		(property "Reference" "U2"
			(at -74.416158 -44.488608 0)
			(unlocked yes)
			(layer "F.SilkS")
			(effects
				(font
					(size 1.6002 1.1938)
					(thickness 0.1524)
				)
				(justify left)
			)
		)
		(property "Value" ""
			(at 0 0 90)
			(layer "F.Fab")
			(effects
				(font
					(size 1.27 1.27)
				)
			)
		)
		(duplicate_pad_numbers_are_jumpers no)
		(pad "AG45" smd circle
			(at -1.613916 -14.856714 270)
			(size 0.4318 0.4318)
			(layers "F.Cu" "F.Mask" "F.Paste")
			(net "GND")
		)
		(pad "AG48" smd circle
			(at 2.427732 -14.746732 270)
			(size 0.4318 0.4318)
			(layers "F.Cu" "F.Mask" "F.Paste")
			(net "M_C_CPU0_SB_RSP<0>")
		)
		(pad "AG50" smd circle
			(at 4.055618 -14.746732 270)
			(size 0.4318 0.4318)
			(layers "F.Cu" "F.Mask" "F.Paste")
			(net "M_D_CPU0_SB_RSP<1>")
		)
		(pad "AG52" smd circle
			(at 5.68325 -14.746732 270)
			(size 0.4318 0.4318)
			(layers "F.Cu" "F.Mask" "F.Paste")
			(net "GND")
		)
		(pad "AG54" smd circle
			(at 7.311136 -14.746732 270)
			(size 0.4318 0.4318)
			(layers "F.Cu" "F.Mask" "F.Paste")
			(net "M_C_CPU0_SA_CB<6>")
		)
		(pad "AG56" smd circle
			(at 8.939022 -14.746732 270)
			(size 0.4318 0.4318)
			(layers "F.Cu" "F.Mask" "F.Paste")
			(net "M_C_CPU0_SA_CB<3>")
		)
		(pad "AG58" smd circle
			(at 10.566654 -14.746732 270)
			(size 0.4318 0.4318)
			(layers "F.Cu" "F.Mask" "F.Paste")
			(net "GND")
		)
		(pad "AG60" smd circle
			(at 12.19454 -14.746732 270)
			(size 0.4318 0.4318)
			(layers "F.Cu" "F.Mask" "F.Paste")
			(net "M_C_CPU0_SA_DQ<30>")
		)
		(pad "AG62" smd circle
			(at 13.822426 -14.746732 270)
			(size 0.4318 0.4318)
			(layers "F.Cu" "F.Mask" "F.Paste")
			(net "M_C_CPU0_SA_DQ<27>")
		)
		(pad "AG64" smd circle
			(at 15.450058 -14.746732 270)
			(size 0.4318 0.4318)
			(layers "F.Cu" "F.Mask" "F.Paste")
			(net "GND")
		)
		(pad "AG66" smd circle
			(at 17.07769 -14.746732 270)
			(size 0.4318 0.4318)
			(layers "F.Cu" "F.Mask" "F.Paste")
			(net "M_C_CPU0_SA_DQ<14>")
		)
		(pad "AG68" smd circle
			(at 18.705576 -14.746732 270)
			(size 0.4318 0.4318)
			(layers "F.Cu" "F.Mask" "F.Paste")
			(net "M_C_CPU0_SA_DQ<11>")
		)
		(pad "AG70" smd circle
			(at 20.333462 -14.746732 270)
			(size 0.4318 0.4318)
			(layers "F.Cu" "F.Mask" "F.Paste")
			(net "GND")
		)
		(pad "AG72" smd circle
			(at 21.961094 -14.746732 270)
			(size 0.4318 0.4318)
			(layers "F.Cu" "F.Mask" "F.Paste")
			(net "M_D_CPU0_SA_DQ<6>")
		)
		(pad "AG74" smd circle
			(at 23.58898 -14.746732 270)
			(size 0.4318 0.4318)
			(layers "F.Cu" "F.Mask" "F.Paste")
			(net "M_D_CPU0_SA_DQ<3>")
		)
		(pad "AG76" smd circle
			(at 25.216612 -14.746732 270)
			(size 0.4318 0.4318)
			(layers "F.Cu" "F.Mask" "F.Paste")
			(net "GND")
		)
		(pad "AG78" smd circle
			(at 26.844498 -14.746732 270)
			(size 0.4318 0.4318)
			(layers "F.Cu" "F.Mask" "F.Paste")
			(net "PVCCFA_EHV_FIVRA_CPU0")
		)
		(pad "AG80" smd circle
			(at 28.472384 -14.746732 270)
			(size 0.4318 0.4318)
			(layers "F.Cu" "F.Mask" "F.Paste")
			(net "UPI_CPU1_CPU0_P2P2_DN<15>")
		)
		(pad "AG82" smd circle
			(at 30.100016 -14.746732 270)
			(size 0.4318 0.4318)
			(layers "F.Cu" "F.Mask" "F.Paste")
			(net "UPI_CPU1_CPU0_P2P2_DP<12>")
		)
		(pad "AG84" smd circle
			(at 31.727902 -14.746732 270)
			(size 0.4318 0.4318)
			(layers "F.Cu" "F.Mask" "F.Paste")
			(net "GND")
		)
		(pad "AG86" smd circle
			(at 33.355534 -14.746732 270)
			(size 0.4318 0.4318)
			(layers "F.Cu" "F.Mask" "F.Paste")
			(net "P5E_CPU0_PE4_TX_DN<8>")
		)
		(pad "AG88" smd circle
			(at 34.98342 -14.746732 270)
			(size 0.4318 0.4318)
			(layers "F.Cu" "F.Mask" "F.Paste")
			(net "GND")
		)
		(pad "AG90" smd circle
			(at 36.611306 -14.746732 270)
			(size 0.4318 0.4318)
			(layers "F.Cu" "F.Mask" "F.Paste")
			(net "P5E_CPU0_PE4_RX_DP<8>")
		)
		(pad "AH2" smd circle
			(at -36.611306 -14.387068 270)
			(size 0.4318 0.4318)
			(layers "F.Cu" "F.Mask" "F.Paste")
			(net "UPI_CPU0_CPU1_P0P1_DN<9>")
		)
		(pad "AH4" smd circle
			(at -34.98342 -14.387068 270)
			(size 0.4318 0.4318)
			(layers "F.Cu" "F.Mask" "F.Paste")
			(net "GND")
		)
		(pad "AH6" smd circle
			(at -33.355534 -14.387068 270)
			(size 0.4318 0.4318)
			(layers "F.Cu" "F.Mask" "F.Paste")
			(net "UPI_CPU1_CPU0_P1P0_DN<9>")
		)
		(pad "AH8" smd circle
			(at -31.727902 -14.387068 270)
			(size 0.4318 0.4318)
			(layers "F.Cu" "F.Mask" "F.Paste")
			(net "GND")
		)
		(pad "AH10" smd circle
			(at -30.100016 -14.387068 270)
			(size 0.4318 0.4318)
			(layers "F.Cu" "F.Mask" "F.Paste")
			(net "P5E_CPU0_PE0_RX_DP<9>")
		)
		(pad "AH12" smd circle
			(at -28.472384 -14.387068 270)
			(size 0.4318 0.4318)
			(layers "F.Cu" "F.Mask" "F.Paste")
			(net "GND")
		)
		(pad "AH14" smd circle
			(at -26.844498 -14.387068 270)
			(size 0.4318 0.4318)
			(layers "F.Cu" "F.Mask" "F.Paste")
			(net "P5E_CPU0_PE0_TX_DP<8>")
		)
		(pad "AH16" smd circle
			(at -25.216612 -14.387068 270)
			(size 0.4318 0.4318)
			(layers "F.Cu" "F.Mask" "F.Paste")
			(net "GND")
		)
		(pad "AH18" smd circle
			(at -23.58898 -14.387068 270)
			(size 0.4318 0.4318)
			(layers "F.Cu" "F.Mask" "F.Paste")
			(net "M_C_CPU0_SB_DQS_DP<8>")
		)
		(pad "AH20" smd circle
			(at -21.961094 -14.387068 270)
			(size 0.4318 0.4318)
			(layers "F.Cu" "F.Mask" "F.Paste")
			(net "GND")
		)
		(pad "AH22" smd circle
			(at -20.333462 -14.387068 270)
			(size 0.4318 0.4318)
			(layers "F.Cu" "F.Mask" "F.Paste")
			(net "GND")
		)
		(pad "AH24" smd circle
			(at -18.705576 -14.387068 270)
			(size 0.4318 0.4318)
			(layers "F.Cu" "F.Mask" "F.Paste")
			(net "M_D_CPU0_SB_DQS_DP<7>")
		)
		(pad "AH26" smd circle
			(at -17.07769 -14.387068 270)
			(size 0.4318 0.4318)
			(layers "F.Cu" "F.Mask" "F.Paste")
			(net "GND")
		)
		(pad "AH28" smd circle
			(at -15.450058 -14.387068 270)
			(size 0.4318 0.4318)
			(layers "F.Cu" "F.Mask" "F.Paste")
			(net "GND")
		)
		(pad "AH30" smd circle
			(at -13.822426 -14.387068 270)
			(size 0.4318 0.4318)
			(layers "F.Cu" "F.Mask" "F.Paste")
			(net "M_C_CPU0_SB_DQS_DP<6>")
		)
		(pad "AH32" smd circle
			(at -12.19454 -14.387068 270)
			(size 0.4318 0.4318)
			(layers "F.Cu" "F.Mask" "F.Paste")
			(net "GND")
		)
		(pad "AH34" smd circle
			(at -10.566654 -14.387068 270)
			(size 0.4318 0.4318)
			(layers "F.Cu" "F.Mask" "F.Paste")
			(net "GND")
		)
		(pad "AH36" smd circle
			(at -8.939022 -14.387068 270)
			(size 0.4318 0.4318)
			(layers "F.Cu" "F.Mask" "F.Paste")
			(net "M_C_CPU0_SB_DQS_DP<5>")
		)
		(pad "AH38" smd circle
			(at -7.311136 -14.387068 270)
			(size 0.4318 0.4318)
			(layers "F.Cu" "F.Mask" "F.Paste")
			(net "GND")
		)
		(pad "AH40" smd circle
			(at -5.68325 -14.387068 270)
			(size 0.4318 0.4318)
			(layers "F.Cu" "F.Mask" "F.Paste")
			(net "GND")
		)
		(pad "AH42" smd circle
			(at -4.055618 -14.387068 270)
			(size 0.4318 0.4318)
			(layers "F.Cu" "F.Mask" "F.Paste")
			(net "M_D_CPU0_SB_PAR")
		)
		(pad "AH44" smd circle
			(at -2.427732 -14.387068 270)
			(size 0.4318 0.4318)
			(layers "F.Cu" "F.Mask" "F.Paste")
			(net "GND")
		)
		(pad "AH47" smd circle
			(at 1.613916 -14.277086 270)
			(size 0.4318 0.4318)
			(layers "F.Cu" "F.Mask" "F.Paste")
			(net "GND")
		)
		(pad "AH49" smd circle
			(at 3.241802 -14.277086 270)
			(size 0.4318 0.4318)
			(layers "F.Cu" "F.Mask" "F.Paste")
			(net "M_C_CPU0_CLK_DP<1>")
		)
		(pad "AH51" smd circle
			(at 4.869434 -14.277086 270)
			(size 0.4318 0.4318)
			(layers "F.Cu" "F.Mask" "F.Paste")
			(net "GND")
		)
		(pad "AH53" smd circle
			(at 6.49732 -14.277086 270)
			(size 0.4318 0.4318)
			(layers "F.Cu" "F.Mask" "F.Paste")
			(net "GND")
		)
		(pad "AH55" smd circle
			(at 8.124952 -14.277086 270)
			(size 0.4318 0.4318)
			(layers "F.Cu" "F.Mask" "F.Paste")
			(net "M_C_CPU0_SA_DQS_DN<9>")
		)
		(pad "AH57" smd circle
			(at 9.752838 -14.277086 270)
			(size 0.4318 0.4318)
			(layers "F.Cu" "F.Mask" "F.Paste")
			(net "GND")
		)
		(pad "AH59" smd circle
			(at 11.380724 -14.277086 270)
			(size 0.4318 0.4318)
			(layers "F.Cu" "F.Mask" "F.Paste")
			(net "GND")
		)
		(pad "AH61" smd circle
			(at 13.008356 -14.277086 270)
			(size 0.4318 0.4318)
			(layers "F.Cu" "F.Mask" "F.Paste")
			(net "M_C_CPU0_SA_DQS_DP<8>")
		)
		(pad "AH63" smd circle
			(at 14.635988 -14.277086 270)
			(size 0.4318 0.4318)
			(layers "F.Cu" "F.Mask" "F.Paste")
			(net "GND")
		)
		(pad "AH65" smd circle
			(at 16.263874 -14.277086 270)
			(size 0.4318 0.4318)
			(layers "F.Cu" "F.Mask" "F.Paste")
			(net "GND")
		)
		(pad "AH67" smd circle
			(at 17.89176 -14.277086 270)
			(size 0.4318 0.4318)
			(layers "F.Cu" "F.Mask" "F.Paste")
			(net "M_C_CPU0_SA_DQS_DN<6>")
		)
		(pad "AH69" smd circle
			(at 19.519392 -14.277086 270)
			(size 0.4318 0.4318)
			(layers "F.Cu" "F.Mask" "F.Paste")
			(net "GND")
		)
		(pad "AH71" smd circle
			(at 21.147278 -14.277086 270)
			(size 0.4318 0.4318)
			(layers "F.Cu" "F.Mask" "F.Paste")
			(net "GND")
		)
		(pad "AH73" smd circle
			(at 22.77491 -14.277086 270)
			(size 0.4318 0.4318)
			(layers "F.Cu" "F.Mask" "F.Paste")
			(net "M_D_CPU0_SA_DQS_DN<5>")
		)
		(pad "AH75" smd circle
			(at 24.402796 -14.277086 270)
			(size 0.4318 0.4318)
			(layers "F.Cu" "F.Mask" "F.Paste")
			(net "GND")
		)
		(pad "AH77" smd circle
			(at 26.030682 -14.277086 270)
			(size 0.4318 0.4318)
			(layers "F.Cu" "F.Mask" "F.Paste")
			(net "GND")
		)
		(pad "AH79" smd circle
			(at 27.658314 -14.277086 270)
			(size 0.4318 0.4318)
			(layers "F.Cu" "F.Mask" "F.Paste")
			(net "GND")
		)
		(pad "AH81" smd circle
			(at 29.2862 -14.277086 270)
			(size 0.4318 0.4318)
			(layers "F.Cu" "F.Mask" "F.Paste")
			(net "UPI_CPU1_CPU0_P2P2_DP<13>")
		)
		(pad "AH83" smd circle
			(at 30.914086 -14.277086 270)
			(size 0.4318 0.4318)
			(layers "F.Cu" "F.Mask" "F.Paste")
			(net "GND")
		)
		(pad "AH85" smd circle
			(at 32.541718 -14.277086 270)
			(size 0.4318 0.4318)
			(layers "F.Cu" "F.Mask" "F.Paste")
			(net "PVCCFA_EHV_FIVRA_CPU0")
		)
		(pad "AH87" smd circle
			(at 34.169604 -14.277086 270)
			(size 0.4318 0.4318)
			(layers "F.Cu" "F.Mask" "F.Paste")
			(net "P5E_CPU0_PE4_TX_DP<8>")
		)
		(pad "AH89" smd circle
			(at 35.797236 -14.277086 270)
			(size 0.4318 0.4318)
			(layers "F.Cu" "F.Mask" "F.Paste")
			(net "PVCCFA_EHV_FIVRA_CPU0")
		)
		(pad "AH91" smd oval
			(at 37.425122 -14.277086)
			(size 0.381 0.4826)
			(drill
				(offset 0 -0.0508)
			)
			(layers "F.Cu" "F.Mask" "F.Paste")
			(net "P5E_CPU0_PE4_RX_DN<8>")
		)
		(pad "AJ1" smd oval
			(at -37.425122 -13.916914 180)
			(size 0.381 0.4826)
			(drill
				(offset 0 -0.0508)
			)
			(layers "F.Cu" "F.Mask" "F.Paste")
			(net "UPI_CPU0_CPU1_P0P1_DP<10>")
		)
		(pad "AJ3" smd circle
			(at -35.797236 -13.916914 270)
			(size 0.4318 0.4318)
			(layers "F.Cu" "F.Mask" "F.Paste")
			(net "PVCCFA_EHV_CPU0")
		)
		(pad "AJ5" smd circle
			(at -34.169604 -13.916914 270)
			(size 0.4318 0.4318)
			(layers "F.Cu" "F.Mask" "F.Paste")
			(net "UPI_CPU1_CPU0_P1P0_DP<9>")
		)
		(pad "AJ7" smd circle
			(at -32.541718 -13.916914 270)
			(size 0.4318 0.4318)
			(layers "F.Cu" "F.Mask" "F.Paste")
			(net "PVCCFA_EHV_FIVRA_CPU0")
		)
		(pad "AJ9" smd circle
			(at -30.914086 -13.916914 270)
			(size 0.4318 0.4318)
			(layers "F.Cu" "F.Mask" "F.Paste")
			(net "P5E_CPU0_PE0_RX_DN<9>")
		)
		(pad "AJ11" smd circle
			(at -29.2862 -13.916914 270)
			(size 0.4318 0.4318)
			(layers "F.Cu" "F.Mask" "F.Paste")
			(net "PVCCFA_EHV_FIVRA_CPU0")
		)
		(pad "AJ13" smd circle
			(at -27.658314 -13.916914 270)
			(size 0.4318 0.4318)
			(layers "F.Cu" "F.Mask" "F.Paste")
			(net "P5E_CPU0_PE0_TX_DN<8>")
		)
		(pad "AJ15" smd circle
			(at -26.030682 -13.916914 270)
			(size 0.4318 0.4318)
			(layers "F.Cu" "F.Mask" "F.Paste")
			(net "PVCCFA_EHV_FIVRA_CPU0")
		)
		(pad "AJ17" smd circle
			(at -24.402796 -13.916914 270)
			(size 0.4318 0.4318)
			(layers "F.Cu" "F.Mask" "F.Paste")
			(net "M_C_CPU0_SB_DQ<31>")
		)
		(pad "AJ19" smd circle
			(at -22.77491 -13.916914 270)
			(size 0.4318 0.4318)
			(layers "F.Cu" "F.Mask" "F.Paste")
			(net "GND")
		)
		(pad "AJ21" smd circle
			(at -21.147278 -13.916914 270)
			(size 0.4318 0.4318)
			(layers "F.Cu" "F.Mask" "F.Paste")
			(net "M_D_CPU0_SB_DQS_DN<3>")
		)
		(pad "AJ23" smd circle
			(at -19.519392 -13.916914 270)
			(size 0.4318 0.4318)
			(layers "F.Cu" "F.Mask" "F.Paste")
			(net "GND")
		)
		(pad "AJ25" smd circle
			(at -17.89176 -13.916914 270)
			(size 0.4318 0.4318)
			(layers "F.Cu" "F.Mask" "F.Paste")
			(net "GND")
		)
		(pad "AJ27" smd circle
			(at -16.263874 -13.916914 270)
			(size 0.4318 0.4318)
			(layers "F.Cu" "F.Mask" "F.Paste")
			(net "M_D_CPU0_SB_DQS_DN<1>")
		)
		(pad "AJ29" smd circle
			(at -14.635988 -13.916914 270)
			(size 0.4318 0.4318)
			(layers "F.Cu" "F.Mask" "F.Paste")
			(net "GND")
		)
		(pad "AJ31" smd circle
			(at -13.008356 -13.916914 270)
			(size 0.4318 0.4318)
			(layers "F.Cu" "F.Mask" "F.Paste")
			(net "GND")
		)
		(pad "AJ33" smd circle
			(at -11.380724 -13.916914 270)
			(size 0.4318 0.4318)
			(layers "F.Cu" "F.Mask" "F.Paste")
			(net "M_D_CPU0_SB_DQS_DN<0>")
		)
		(pad "AJ35" smd circle
			(at -9.752838 -13.916914 270)
			(size 0.4318 0.4318)
			(layers "F.Cu" "F.Mask" "F.Paste")
			(net "GND")
		)
		(pad "AJ37" smd circle
			(at -8.124952 -13.916914 270)
			(size 0.4318 0.4318)
			(layers "F.Cu" "F.Mask" "F.Paste")
			(net "GND")
		)
		(pad "AJ39" smd circle
			(at -6.49732 -13.916914 270)
			(size 0.4318 0.4318)
			(layers "F.Cu" "F.Mask" "F.Paste")
			(net "M_D_CPU0_SB_DQS_DN<9>")
		)
		(pad "AJ41" smd circle
			(at -4.869434 -13.916914 270)
			(size 0.4318 0.4318)
			(layers "F.Cu" "F.Mask" "F.Paste")
			(net "GND")
		)
		(pad "AJ43" smd circle
			(at -3.241802 -13.916914 270)
			(size 0.4318 0.4318)
			(layers "F.Cu" "F.Mask" "F.Paste")
			(net "GND")
		)
		(pad "AJ45" smd circle
			(at -1.613916 -13.916914 270)
			(size 0.4318 0.4318)
			(layers "F.Cu" "F.Mask" "F.Paste")
			(net "M_D_CPU0_CLK_DN<0>")
		)
		(pad "AJ48" smd circle
			(at 2.427732 -13.806932 270)
			(size 0.4318 0.4318)
			(layers "F.Cu" "F.Mask" "F.Paste")
			(net "GND")
		)
		(pad "AJ50" smd circle
			(at 4.055618 -13.806932 270)
			(size 0.4318 0.4318)
			(layers "F.Cu" "F.Mask" "F.Paste")
			(net "GND")
		)
		(pad "AJ52" smd circle
			(at 5.68325 -13.806932 270)
			(size 0.4318 0.4318)
			(layers "F.Cu" "F.Mask" "F.Paste")
			(net "M_D_CPU0_SA_CA<0>")
		)
		(pad "AJ54" smd circle
			(at 7.311136 -13.806932 270)
			(size 0.4318 0.4318)
			(layers "F.Cu" "F.Mask" "F.Paste")
			(net "GND")
		)
		(pad "AJ56" smd circle
			(at 8.939022 -13.806932 270)
			(size 0.4318 0.4318)
			(layers "F.Cu" "F.Mask" "F.Paste")
			(net "GND")
		)
		(pad "AJ58" smd circle
			(at 10.566654 -13.806932 270)
			(size 0.4318 0.4318)
			(layers "F.Cu" "F.Mask" "F.Paste")
			(net "M_D_CPU0_SA_DQS_DN<4>")
		)
		(pad "AJ60" smd circle
			(at 12.19454 -13.806932 270)
			(size 0.4318 0.4318)
			(layers "F.Cu" "F.Mask" "F.Paste")
			(net "GND")
		)
		(pad "AJ62" smd circle
			(at 13.822426 -13.806932 270)
			(size 0.4318 0.4318)
			(layers "F.Cu" "F.Mask" "F.Paste")
			(net "GND")
		)
		(pad "AJ64" smd circle
			(at 15.450058 -13.806932 270)
			(size 0.4318 0.4318)
			(layers "F.Cu" "F.Mask" "F.Paste")
			(net "M_D_CPU0_SA_DQS_DN<3>")
		)
		(pad "AJ66" smd circle
			(at 17.07769 -13.806932 270)
			(size 0.4318 0.4318)
			(layers "F.Cu" "F.Mask" "F.Paste")
			(net "GND")
		)
		(pad "AJ68" smd circle
			(at 18.705576 -13.806932 270)
			(size 0.4318 0.4318)
			(layers "F.Cu" "F.Mask" "F.Paste")
			(net "GND")
		)
		(pad "AJ70" smd circle
			(at 20.333462 -13.806932 270)
			(size 0.4318 0.4318)
			(layers "F.Cu" "F.Mask" "F.Paste")
			(net "M_D_CPU0_SA_DQS_DN<2>")
		)
		(pad "AJ72" smd circle
			(at 21.961094 -13.806932 270)
			(size 0.4318 0.4318)
			(layers "F.Cu" "F.Mask" "F.Paste")
			(net "GND")
		)
		(pad "AJ74" smd circle
			(at 23.58898 -13.806932 270)
			(size 0.4318 0.4318)
			(layers "F.Cu" "F.Mask" "F.Paste")
			(net "GND")
		)
		(pad "AJ76" smd circle
			(at 25.216612 -13.806932 270)
			(size 0.4318 0.4318)
			(layers "F.Cu" "F.Mask" "F.Paste")
			(net "M_D_CPU0_SA_DQS_DN<1>")
		)
		(pad "AJ78" smd circle
			(at 26.844498 -13.806932 270)
			(size 0.4318 0.4318)
			(layers "F.Cu" "F.Mask" "F.Paste")
			(net "GND")
		)
		(pad "AJ80" smd circle
			(at 28.472384 -13.806932 270)
			(size 0.4318 0.4318)
			(layers "F.Cu" "F.Mask" "F.Paste")
			(net "UPI_CPU1_CPU0_P2P2_DN<13>")
		)
	)
)
